(kicad_pcb
	(version 20260206)
	(generator "pcbnew")
	(generator_version "10.0")
	(general
		(thickness 1.6)
		(legacy_teardrops no)
	)
	(paper "A4")
	(title_block
		(title "12092022_DA0F0TYB4D0_F0T_Panel_BD_Front_D_brd_v02_OCP.brd")
		(comment 1 "Grand Teton / footprints 116-120 of 128")
	)
	(layers
		(0 "F.Cu" signal "TOP")
		(4 "In1.Cu" signal "GND")
		(6 "In2.Cu" signal "GND1")
		(2 "B.Cu" signal "BOTTOM")
		(9 "F.Adhes" user "F.Adhesive")
		(11 "B.Adhes" user "B.Adhesive")
		(13 "F.Paste" user "Package Geometry/Pastemask Top")
		(15 "B.Paste" user "Package Geometry/Pastemask Bottom")
		(5 "F.SilkS" user "Ref Des/Silkscreen Top")
		(7 "B.SilkS" user "Ref Des/Silkscreen Bottom")
		(1 "F.Mask" user "Board Geometry/Soldermask Top")
		(3 "B.Mask" user "Board Geometry/Soldermask Bottom")
		(17 "Dwgs.User" user "User.Drawings")
		(19 "Cmts.User" user "User.Comments")
		(21 "Eco1.User" user "User.Eco1")
		(23 "Eco2.User" user "User.Eco2")
		(25 "Edge.Cuts" user "Board Geometry/Outline")
		(27 "Margin" user)
		(31 "F.CrtYd" user "Package Geometry/Place Bound Top")
		(29 "B.CrtYd" user "Package Geometry/Place Bound Bottom")
		(35 "F.Fab" user "Ref Des/Assembly Top")
		(33 "B.Fab" user "Ref Des/Assembly Bottom")
	)
	(footprint ""
		(layer "F.Cu")
		(at 17.399 -17.145)
		(property "Reference" "R4"
			(at -1.651 0.02667 0)
			(unlocked yes)
			(layer "F.SilkS")
			(effects
				(font
					(size 0.7874 0.5842)
					(thickness 0.1524)
				)
			)
		)
		(property "Value" ""
			(at 0 0 0)
			(layer "F.Fab")
			(effects
				(font
					(size 1.27 1.27)
				)
			)
		)
		(duplicate_pad_numbers_are_jumpers no)
		(fp_line
			(start -0.7874 -0.4064)
			(end 0.7874 -0.4064)
			(stroke
				(width 0.1524)
				(type default)
			)
			(layer "F.SilkS")
		)
		(fp_line
			(start -0.7874 0.4064)
			(end -0.7874 -0.4064)
			(stroke
				(width 0.1524)
				(type default)
			)
			(layer "F.SilkS")
		)
		(fp_line
			(start 0.7874 -0.4064)
			(end 0.7874 0.4064)
			(stroke
				(width 0.1524)
				(type default)
			)
			(layer "F.SilkS")
		)
		(fp_line
			(start 0.7874 0.4064)
			(end -0.7874 0.4064)
			(stroke
				(width 0.1524)
				(type default)
			)
			(layer "F.SilkS")
		)
		(fp_line
			(start -0.67945 -0.305054)
			(end -0.12065 -0.305054)
			(stroke
				(width 0.1)
				(type default)
			)
			(layer "F.Fab")
		)
		(fp_line
			(start -0.67945 0.3048)
			(end -0.67945 -0.305054)
			(stroke
				(width 0.1)
				(type default)
			)
			(layer "F.Fab")
		)
		(fp_line
			(start -0.12065 -0.305054)
			(end -0.12065 -0.2794)
			(stroke
				(width 0.1)
				(type default)
			)
			(layer "F.Fab")
		)
		(fp_line
			(start -0.12065 -0.2794)
			(end 0.12065 -0.2794)
			(stroke
				(width 0.1)
				(type default)
			)
			(layer "F.Fab")
		)
		(fp_line
			(start -0.12065 0.2794)
			(end -0.12065 0.3048)
			(stroke
				(width 0.1)
				(type default)
			)
			(layer "F.Fab")
		)
		(fp_line
			(start -0.12065 0.3048)
			(end -0.67945 0.3048)
			(stroke
				(width 0.1)
				(type default)
			)
			(layer "F.Fab")
		)
		(fp_line
			(start 0.120396 0.2794)
			(end -0.12065 0.2794)
			(stroke
				(width 0.1)
				(type default)
			)
			(layer "F.Fab")
		)
		(fp_line
			(start 0.120396 0.3048)
			(end 0.120396 0.2794)
			(stroke
				(width 0.1)
				(type default)
			)
			(layer "F.Fab")
		)
		(fp_line
			(start 0.12065 -0.3048)
			(end 0.67945 -0.3048)
			(stroke
				(width 0.1)
				(type default)
			)
			(layer "F.Fab")
		)
		(fp_line
			(start 0.12065 -0.2794)
			(end 0.12065 -0.3048)
			(stroke
				(width 0.1)
				(type default)
			)
			(layer "F.Fab")
		)
		(fp_line
			(start 0.67945 -0.3048)
			(end 0.67945 0.3048)
			(stroke
				(width 0.1)
				(type default)
			)
			(layer "F.Fab")
		)
		(fp_line
			(start 0.67945 0.3048)
			(end 0.120396 0.3048)
			(stroke
				(width 0.1)
				(type default)
			)
			(layer "F.Fab")
		)
		(pad "1" smd circle
			(at -0.40005 0)
			(size 0 0)
			(layers "F.Cu" "F.Mask" "F.Paste")
			(net "FM_PFR_LED_BLUE_N")
		)
		(pad "2" smd circle
			(at 0.40005 0)
			(size 0 0)
			(layers "F.Cu" "F.Mask" "F.Paste")
			(net "FM_PFR_LED_BLUE_R_N")
		)
	)
	(footprint ""
		(layer "F.Cu")
		(at 36.703 -21.336 180)
		(property "Reference" "R33"
			(at 2.032 -0.02667 0)
			(unlocked yes)
			(layer "F.SilkS")
			(effects
				(font
					(size 0.7874 0.5842)
					(thickness 0.1524)
				)
			)
		)
		(property "Value" ""
			(at 0 0 180)
			(layer "F.Fab")
			(effects
				(font
					(size 1.27 1.27)
				)
			)
		)
		(duplicate_pad_numbers_are_jumpers no)
		(fp_line
			(start 0.7874 0.4064)
			(end -0.7874 0.4064)
			(stroke
				(width 0.1524)
				(type default)
			)
			(layer "F.SilkS")
		)
		(fp_line
			(start 0.7874 -0.4064)
			(end 0.7874 0.4064)
			(stroke
				(width 0.1524)
				(type default)
			)
			(layer "F.SilkS")
		)
		(fp_line
			(start -0.7874 0.4064)
			(end -0.7874 -0.4064)
			(stroke
				(width 0.1524)
				(type default)
			)
			(layer "F.SilkS")
		)
		(fp_line
			(start -0.7874 -0.4064)
			(end 0.7874 -0.4064)
			(stroke
				(width 0.1524)
				(type default)
			)
			(layer "F.SilkS")
		)
		(fp_line
			(start 0.67945 0.3048)
			(end 0.120396 0.3048)
			(stroke
				(width 0.1)
				(type default)
			)
			(layer "F.Fab")
		)
		(fp_line
			(start 0.67945 -0.3048)
			(end 0.67945 0.3048)
			(stroke
				(width 0.1)
				(type default)
			)
			(layer "F.Fab")
		)
		(fp_line
			(start 0.12065 -0.2794)
			(end 0.12065 -0.3048)
			(stroke
				(width 0.1)
				(type default)
			)
			(layer "F.Fab")
		)
		(fp_line
			(start 0.12065 -0.3048)
			(end 0.67945 -0.3048)
			(stroke
				(width 0.1)
				(type default)
			)
			(layer "F.Fab")
		)
		(fp_line
			(start 0.120396 0.3048)
			(end 0.120396 0.2794)
			(stroke
				(width 0.1)
				(type default)
			)
			(layer "F.Fab")
		)
		(fp_line
			(start 0.120396 0.2794)
			(end -0.12065 0.2794)
			(stroke
				(width 0.1)
				(type default)
			)
			(layer "F.Fab")
		)
		(fp_line
			(start -0.12065 0.3048)
			(end -0.67945 0.3048)
			(stroke
				(width 0.1)
				(type default)
			)
			(layer "F.Fab")
		)
		(fp_line
			(start -0.12065 0.2794)
			(end -0.12065 0.3048)
			(stroke
				(width 0.1)
				(type default)
			)
			(layer "F.Fab")
		)
		(fp_line
			(start -0.12065 -0.2794)
			(end 0.12065 -0.2794)
			(stroke
				(width 0.1)
				(type default)
			)
			(layer "F.Fab")
		)
		(fp_line
			(start -0.12065 -0.305054)
			(end -0.12065 -0.2794)
			(stroke
				(width 0.1)
				(type default)
			)
			(layer "F.Fab")
		)
		(fp_line
			(start -0.67945 0.3048)
			(end -0.67945 -0.305054)
			(stroke
				(width 0.1)
				(type default)
			)
			(layer "F.Fab")
		)
		(fp_line
			(start -0.67945 -0.305054)
			(end -0.12065 -0.305054)
			(stroke
				(width 0.1)
				(type default)
			)
			(layer "F.Fab")
		)
		(pad "1" smd circle
			(at -0.40005 0 180)
			(size 0 0)
			(layers "F.Cu" "F.Mask" "F.Paste")
			(net "P3V3_STBY")
		)
		(pad "2" smd circle
			(at 0.40005 0 180)
			(size 0 0)
			(layers "F.Cu" "F.Mask" "F.Paste")
			(net "THERMAL_ADDR_A1")
		)
	)
	(footprint ""
		(layer "F.Cu")
		(at 12.192 -57.912)
		(property "Reference" "U5"
			(at -3.429 -5.81533 0)
			(unlocked yes)
			(layer "F.SilkS")
			(effects
				(font
					(size 0.7874 0.5842)
					(thickness 0.1524)
				)
				(justify left)
			)
		)
		(property "Value" ""
			(at 0 0 0)
			(layer "F.Fab")
			(effects
				(font
					(size 1.27 1.27)
				)
			)
		)
		(duplicate_pad_numbers_are_jumpers no)
		(fp_line
			(start -2.097532 -3.949954)
			(end -2.097532 3.949954)
			(stroke
				(width 0.1524)
				(type default)
			)
			(layer "F.SilkS")
		)
		(fp_line
			(start -2.097532 3.949954)
			(end 2.097532 3.949954)
			(stroke
				(width 0.1524)
				(type default)
			)
			(layer "F.SilkS")
		)
		(fp_line
			(start -1.409954 -3.949954)
			(end -2.097532 -3.949954)
			(stroke
				(width 0.1524)
				(type default)
			)
			(layer "F.SilkS")
		)
		(fp_line
			(start 0 -2.54)
			(end -1.409954 -3.949954)
			(stroke
				(width 0.1524)
				(type default)
			)
			(layer "F.SilkS")
		)
		(fp_line
			(start 1.409954 -3.949954)
			(end 0 -2.54)
			(stroke
				(width 0.1524)
				(type default)
			)
			(layer "F.SilkS")
		)
		(fp_line
			(start 2.097532 -3.949954)
			(end 1.409954 -3.949954)
			(stroke
				(width 0.1524)
				(type default)
			)
			(layer "F.SilkS")
		)
		(fp_line
			(start 2.097532 3.949954)
			(end 2.097532 -3.949954)
			(stroke
				(width 0.1524)
				(type default)
			)
			(layer "F.SilkS")
		)
		(fp_poly
			(pts
				(xy -2.421128 -5.1308) (xy -3.437128 -5.1308) (xy -2.929128 -4.1148)
			)
			(stroke
				(width 0)
				(type default)
			)
			(fill yes)
			(layer "F.SilkS")
		)
		(fp_line
			(start -2.249932 -3.949954)
			(end -2.249932 3.949954)
			(stroke
				(width 0.1)
				(type default)
			)
			(layer "F.Fab")
		)
		(fp_line
			(start -2.249932 3.949954)
			(end 2.249932 3.949954)
			(stroke
				(width 0.1)
				(type default)
			)
			(layer "F.Fab")
		)
		(fp_line
			(start 2.249932 -3.949954)
			(end -2.249932 -3.949954)
			(stroke
				(width 0.1)
				(type default)
			)
			(layer "F.Fab")
		)
		(fp_line
			(start 2.249932 3.949954)
			(end 2.249932 -3.949954)
			(stroke
				(width 0.1)
				(type default)
			)
			(layer "F.Fab")
		)
		(fp_poly
			(pts
				(xy -4.7498 -4.182872) (xy -4.7498 -3.166872) (xy -3.7338 -3.674872)
			)
			(stroke
				(width 0)
				(type default)
			)
			(fill yes)
			(layer "F.Fab")
		)
		(pad "1" smd rect
			(at -2.925064 -3.674872 270)
			(size 0.6096 1.3716)
			(layers "F.Cu" "F.Mask" "F.Paste")
			(net "Net_87")
		)
		(pad "2" smd rect
			(at -2.925064 -2.925064 270)
			(size 0.4064 1.3716)
			(layers "F.Cu" "F.Mask" "F.Paste")
			(net "PCA9539_A1")
		)
		(pad "3" smd rect
			(at -2.925064 -2.275078 270)
			(size 0.4064 1.3716)
			(layers "F.Cu" "F.Mask" "F.Paste")
			(net "RST_SMB_R_N")
		)
		(pad "4" smd rect
			(at -2.925064 -1.625092 270)
			(size 0.4064 1.3716)
			(layers "F.Cu" "F.Mask" "F.Paste")
			(net "Net_86")
		)
		(pad "5" smd rect
			(at -2.925064 -0.975106 270)
			(size 0.4064 1.3716)
			(layers "F.Cu" "F.Mask" "F.Paste")
			(net "Net_85")
		)
		(pad "6" smd rect
			(at -2.925064 -0.32512 270)
			(size 0.4064 1.3716)
			(layers "F.Cu" "F.Mask" "F.Paste")
			(net "Net_84")
		)
		(pad "7" smd rect
			(at -2.925064 0.32512 270)
			(size 0.4064 1.3716)
			(layers "F.Cu" "F.Mask" "F.Paste")
			(net "Net_83")
		)
		(pad "8" smd rect
			(at -2.925064 0.975106 270)
			(size 0.4064 1.3716)
			(layers "F.Cu" "F.Mask" "F.Paste")
			(net "Net_82")
		)
		(pad "9" smd rect
			(at -2.925064 1.625092 270)
			(size 0.4064 1.3716)
			(layers "F.Cu" "F.Mask" "F.Paste")
			(net "REV_ID<2>")
		)
		(pad "10" smd rect
			(at -2.925064 2.275078 270)
			(size 0.4064 1.3716)
			(layers "F.Cu" "F.Mask" "F.Paste")
			(net "REV_ID<1>")
		)
		(pad "11" smd rect
			(at -2.925064 2.925064 270)
			(size 0.4064 1.3716)
			(layers "F.Cu" "F.Mask" "F.Paste")
			(net "REV_ID<0>")
		)
		(pad "12" smd rect
			(at -2.925064 3.674872 270)
			(size 0.6096 1.3716)
			(layers "F.Cu" "F.Mask" "F.Paste")
			(net "GND")
		)
		(pad "13" smd rect
			(at 2.925064 3.674872 270)
			(size 0.6096 1.3716)
			(layers "F.Cu" "F.Mask" "F.Paste")
			(net "Net_81")
		)
		(pad "14" smd rect
			(at 2.925064 2.925064 270)
			(size 0.4064 1.3716)
			(layers "F.Cu" "F.Mask" "F.Paste")
			(net "Net_80")
		)
		(pad "15" smd rect
			(at 2.925064 2.275078 270)
			(size 0.4064 1.3716)
			(layers "F.Cu" "F.Mask" "F.Paste")
			(net "Net_79")
		)
		(pad "16" smd rect
			(at 2.925064 1.625092 270)
			(size 0.4064 1.3716)
			(layers "F.Cu" "F.Mask" "F.Paste")
			(net "Net_78")
		)
		(pad "17" smd rect
			(at 2.925064 0.975106 270)
			(size 0.4064 1.3716)
			(layers "F.Cu" "F.Mask" "F.Paste")
			(net "Net_77")
		)
		(pad "18" smd rect
			(at 2.925064 0.32512 270)
			(size 0.4064 1.3716)
			(layers "F.Cu" "F.Mask" "F.Paste")
			(net "Net_76")
		)
		(pad "19" smd rect
			(at 2.925064 -0.32512 270)
			(size 0.4064 1.3716)
			(layers "F.Cu" "F.Mask" "F.Paste")
			(net "SYSTEM_FAULT_ID_LED")
		)
		(pad "20" smd rect
			(at 2.925064 -0.975106 270)
			(size 0.4064 1.3716)
			(layers "F.Cu" "F.Mask" "F.Paste")
			(net "PWR_LED")
		)
		(pad "21" smd rect
			(at 2.925064 -1.625092 270)
			(size 0.4064 1.3716)
			(layers "F.Cu" "F.Mask" "F.Paste")
			(net "PCA9539_A0")
		)
		(pad "22" smd rect
			(at 2.925064 -2.275078 270)
			(size 0.4064 1.3716)
			(layers "F.Cu" "F.Mask" "F.Paste")
			(net "SMB_EXP_SCL")
		)
		(pad "23" smd rect
			(at 2.925064 -2.925064 270)
			(size 0.4064 1.3716)
			(layers "F.Cu" "F.Mask" "F.Paste")
			(net "SMB_EXP_SDA")
		)
		(pad "24" smd rect
			(at 2.925064 -3.674872 270)
			(size 0.6096 1.3716)
			(layers "F.Cu" "F.Mask" "F.Paste")
			(net "P3V3_STBY")
		)
	)
	(footprint ""
		(layer "F.Cu")
		(at 14.605 -51.181)
		(property "Reference" "C11"
			(at 2.032 -0.35433 0)
			(unlocked yes)
			(layer "F.SilkS")
			(effects
				(font
					(size 0.7874 0.5842)
					(thickness 0.1524)
				)
			)
		)
		(property "Value" ""
			(at 0 0 0)
			(layer "F.Fab")
			(effects
				(font
					(size 1.27 1.27)
				)
			)
		)
		(duplicate_pad_numbers_are_jumpers no)
		(fp_line
			(start -0.7874 -0.4064)
			(end 0.7874 -0.4064)
			(stroke
				(width 0.1524)
				(type default)
			)
			(layer "F.SilkS")
		)
		(fp_line
			(start -0.7874 0.4064)
			(end -0.7874 -0.4064)
			(stroke
				(width 0.1524)
				(type default)
			)
			(layer "F.SilkS")
		)
		(fp_line
			(start 0.7874 -0.4064)
			(end 0.7874 0.4064)
			(stroke
				(width 0.1524)
				(type default)
			)
			(layer "F.SilkS")
		)
		(fp_line
			(start 0.7874 0.4064)
			(end -0.7874 0.4064)
			(stroke
				(width 0.1524)
				(type default)
			)
			(layer "F.SilkS")
		)
		(fp_line
			(start -0.67945 -0.305054)
			(end -0.12065 -0.305054)
			(stroke
				(width 0.1)
				(type default)
			)
			(layer "F.Fab")
		)
		(fp_line
			(start -0.67945 0.3048)
			(end -0.67945 -0.305054)
			(stroke
				(width 0.1)
				(type default)
			)
			(layer "F.Fab")
		)
		(fp_line
			(start -0.12065 -0.305054)
			(end -0.12065 -0.2794)
			(stroke
				(width 0.1)
				(type default)
			)
			(layer "F.Fab")
		)
		(fp_line
			(start -0.12065 -0.2794)
			(end 0.12065 -0.2794)
			(stroke
				(width 0.1)
				(type default)
			)
			(layer "F.Fab")
		)
		(fp_line
			(start -0.12065 0.2794)
			(end -0.12065 0.3048)
			(stroke
				(width 0.1)
				(type default)
			)
			(layer "F.Fab")
		)
		(fp_line
			(start -0.12065 0.3048)
			(end -0.67945 0.3048)
			(stroke
				(width 0.1)
				(type default)
			)
			(layer "F.Fab")
		)
		(fp_line
			(start 0.120396 0.2794)
			(end -0.12065 0.2794)
			(stroke
				(width 0.1)
				(type default)
			)
			(layer "F.Fab")
		)
		(fp_line
			(start 0.120396 0.3048)
			(end 0.120396 0.2794)
			(stroke
				(width 0.1)
				(type default)
			)
			(layer "F.Fab")
		)
		(fp_line
			(start 0.12065 -0.3048)
			(end 0.67945 -0.3048)
			(stroke
				(width 0.1)
				(type default)
			)
			(layer "F.Fab")
		)
		(fp_line
			(start 0.12065 -0.2794)
			(end 0.12065 -0.3048)
			(stroke
				(width 0.1)
				(type default)
			)
			(layer "F.Fab")
		)
		(fp_line
			(start 0.67945 -0.3048)
			(end 0.67945 0.3048)
			(stroke
				(width 0.1)
				(type default)
			)
			(layer "F.Fab")
		)
		(fp_line
			(start 0.67945 0.3048)
			(end 0.120396 0.3048)
			(stroke
				(width 0.1)
				(type default)
			)
			(layer "F.Fab")
		)
		(pad "1" smd circle
			(at -0.40005 0)
			(size 0 0)
			(layers "F.Cu" "F.Mask" "F.Paste")
			(net "P3V3_STBY")
		)
		(pad "2" smd circle
			(at 0.40005 0)
			(size 0 0)
			(layers "F.Cu" "F.Mask" "F.Paste")
			(net "GND")
		)
	)
	(footprint ""
		(layer "F.Cu")
		(at 19.558 -22.098)
		(property "Reference" "R30"
			(at 0.381 -4.16433 0)
			(unlocked yes)
			(layer "F.SilkS")
			(effects
				(font
					(size 0.7874 0.5842)
					(thickness 0.1524)
				)
			)
		)
		(property "Value" ""
			(at 0 0 0)
			(layer "F.Fab")
			(effects
				(font
					(size 1.27 1.27)
				)
			)
		)
		(duplicate_pad_numbers_are_jumpers no)
		(fp_line
			(start -0.7874 -0.4064)
			(end 0.7874 -0.4064)
			(stroke
				(width 0.1524)
				(type default)
			)
			(layer "F.SilkS")
		)
		(fp_line
			(start -0.7874 0.4064)
			(end -0.7874 -0.4064)
			(stroke
				(width 0.1524)
				(type default)
			)
			(layer "F.SilkS")
		)
		(fp_line
			(start 0.7874 -0.4064)
			(end 0.7874 0.4064)
			(stroke
				(width 0.1524)
				(type default)
			)
			(layer "F.SilkS")
		)
		(fp_line
			(start 0.7874 0.4064)
			(end -0.7874 0.4064)
			(stroke
				(width 0.1524)
				(type default)
			)
			(layer "F.SilkS")
		)
		(fp_line
			(start -0.67945 -0.305054)
			(end -0.12065 -0.305054)
			(stroke
				(width 0.1)
				(type default)
			)
			(layer "F.Fab")
		)
		(fp_line
			(start -0.67945 0.3048)
			(end -0.67945 -0.305054)
			(stroke
				(width 0.1)
				(type default)
			)
			(layer "F.Fab")
		)
		(fp_line
			(start -0.12065 -0.305054)
			(end -0.12065 -0.2794)
			(stroke
				(width 0.1)
				(type default)
			)
			(layer "F.Fab")
		)
		(fp_line
			(start -0.12065 -0.2794)
			(end 0.12065 -0.2794)
			(stroke
				(width 0.1)
				(type default)
			)
			(layer "F.Fab")
		)
		(fp_line
			(start -0.12065 0.2794)
			(end -0.12065 0.3048)
			(stroke
				(width 0.1)
				(type default)
			)
			(layer "F.Fab")
		)
		(fp_line
			(start -0.12065 0.3048)
			(end -0.67945 0.3048)
			(stroke
				(width 0.1)
				(type default)
			)
			(layer "F.Fab")
		)
		(fp_line
			(start 0.120396 0.2794)
			(end -0.12065 0.2794)
			(stroke
				(width 0.1)
				(type default)
			)
			(layer "F.Fab")
		)
		(fp_line
			(start 0.120396 0.3048)
			(end 0.120396 0.2794)
			(stroke
				(width 0.1)
				(type default)
			)
			(layer "F.Fab")
		)
		(fp_line
			(start 0.12065 -0.3048)
			(end 0.67945 -0.3048)
			(stroke
				(width 0.1)
				(type default)
			)
			(layer "F.Fab")
		)
		(fp_line
			(start 0.12065 -0.2794)
			(end 0.12065 -0.3048)
			(stroke
				(width 0.1)
				(type default)
			)
			(layer "F.Fab")
		)
		(fp_line
			(start 0.67945 -0.3048)
			(end 0.67945 0.3048)
			(stroke
				(width 0.1)
				(type default)
			)
			(layer "F.Fab")
		)
		(fp_line
			(start 0.67945 0.3048)
			(end 0.120396 0.3048)
			(stroke
				(width 0.1)
				(type default)
			)
			(layer "F.Fab")
		)
		(pad "1" smd circle
			(at -0.40005 0)
			(size 0 0)
			(layers "F.Cu" "F.Mask" "F.Paste")
			(net "P3V3_STBY")
		)
		(pad "2" smd circle
			(at 0.40005 0)
			(size 0 0)
			(layers "F.Cu" "F.Mask" "F.Paste")
			(net "SMB_TMP75_SCL")
		)
	)
)
